(kicad_pcb
	(version 20260206)
	(generator "pcbnew")
	(generator_version "10.0")
	(general
		(thickness 1.6)
		(legacy_teardrops no)
	)
	(paper "A4")
	(title_block
		(title "04192023_DAF0TMB3IC0_F0TG_MB_C_brd_V02_OCP.brd")
		(comment 1 "Grand Teton / footprints 7684-7689 of 8354")
	)
	(layers
		(0 "F.Cu" signal "TOP")
		(4 "In1.Cu" signal "GND")
		(6 "In2.Cu" signal "IN1")
		(8 "In3.Cu" signal "GND1")
		(10 "In4.Cu" signal "IN2")
		(12 "In5.Cu" signal "GND2")
		(14 "In6.Cu" signal "IN3")
		(16 "In7.Cu" signal "GND3")
		(18 "In8.Cu" signal "VCC")
		(20 "In9.Cu" signal "VCC1")
		(22 "In10.Cu" signal "GND4")
		(24 "In11.Cu" signal "IN4")
		(26 "In12.Cu" signal "GND5")
		(28 "In13.Cu" signal "IN5")
		(30 "In14.Cu" signal "GND6")
		(32 "In15.Cu" signal "IN6")
		(34 "In16.Cu" signal "GND7")
		(2 "B.Cu" signal "BOTTOM")
		(9 "F.Adhes" user "F.Adhesive")
		(11 "B.Adhes" user "B.Adhesive")
		(13 "F.Paste" user "Package Geometry/Pastemask Top")
		(15 "B.Paste" user "Package Geometry/Pastemask Bottom")
		(5 "F.SilkS" user "Ref Des/Silkscreen Top")
		(7 "B.SilkS" user "Ref Des/Silkscreen Bottom")
		(1 "F.Mask" user "Board Geometry/Soldermask Top")
		(3 "B.Mask" user "Board Geometry/Soldermask Bottom")
		(17 "Dwgs.User" user "User.Drawings")
		(19 "Cmts.User" user "User.Comments")
		(21 "Eco1.User" user "User.Eco1")
		(23 "Eco2.User" user "User.Eco2")
		(25 "Edge.Cuts" user "Board Geometry/Outline")
		(27 "Margin" user)
		(31 "F.CrtYd" user "Package Geometry/Place Bound Top")
		(29 "B.CrtYd" user "Package Geometry/Place Bound Bottom")
		(35 "F.Fab" user "Ref Des/Assembly Top")
		(33 "B.Fab" user "Ref Des/Assembly Bottom")
	)
	(footprint ""
		(layer "B.Cu")
		(at 13.241782 -409.624784 180)
		(property "Reference" "PR6821"
			(at 0 0 0)
			(layer "B.SilkS")
			(hide yes)
			(effects
				(font
					(size 1.27 1.27)
				)
				(justify mirror)
			)
		)
		(property "Value" ""
			(at 0 0 0)
			(layer "B.Fab")
			(effects
				(font
					(size 1.27 1.27)
				)
				(justify mirror)
			)
		)
		(duplicate_pad_numbers_are_jumpers no)
		(fp_line
			(start 0.7874 0.4064)
			(end 0.7874 -0.4064)
			(stroke
				(width 0.1524)
				(type default)
			)
			(layer "B.SilkS")
		)
		(fp_line
			(start 0.7874 -0.4064)
			(end -0.7874 -0.4064)
			(stroke
				(width 0.1524)
				(type default)
			)
			(layer "B.SilkS")
		)
		(fp_line
			(start -0.7874 0.4064)
			(end 0.7874 0.4064)
			(stroke
				(width 0.1524)
				(type default)
			)
			(layer "B.SilkS")
		)
		(fp_line
			(start -0.7874 -0.4064)
			(end -0.7874 0.4064)
			(stroke
				(width 0.1524)
				(type default)
			)
			(layer "B.SilkS")
		)
		(fp_line
			(start 0.67945 0.3048)
			(end 0.67945 -0.305054)
			(stroke
				(width 0.1)
				(type default)
			)
			(layer "B.Fab")
		)
		(fp_line
			(start 0.67945 -0.305054)
			(end 0.12065 -0.305054)
			(stroke
				(width 0.1)
				(type default)
			)
			(layer "B.Fab")
		)
		(fp_line
			(start 0.12065 0.3048)
			(end 0.67945 0.3048)
			(stroke
				(width 0.1)
				(type default)
			)
			(layer "B.Fab")
		)
		(fp_line
			(start 0.12065 0.2794)
			(end 0.12065 0.3048)
			(stroke
				(width 0.1)
				(type default)
			)
			(layer "B.Fab")
		)
		(fp_line
			(start 0.12065 -0.2794)
			(end -0.12065 -0.2794)
			(stroke
				(width 0.1)
				(type default)
			)
			(layer "B.Fab")
		)
		(fp_line
			(start 0.12065 -0.305054)
			(end 0.12065 -0.2794)
			(stroke
				(width 0.1)
				(type default)
			)
			(layer "B.Fab")
		)
		(fp_line
			(start -0.120396 0.3048)
			(end -0.120396 0.2794)
			(stroke
				(width 0.1)
				(type default)
			)
			(layer "B.Fab")
		)
		(fp_line
			(start -0.120396 0.2794)
			(end 0.12065 0.2794)
			(stroke
				(width 0.1)
				(type default)
			)
			(layer "B.Fab")
		)
		(fp_line
			(start -0.12065 -0.2794)
			(end -0.12065 -0.3048)
			(stroke
				(width 0.1)
				(type default)
			)
			(layer "B.Fab")
		)
		(fp_line
			(start -0.12065 -0.3048)
			(end -0.67945 -0.3048)
			(stroke
				(width 0.1)
				(type default)
			)
			(layer "B.Fab")
		)
		(fp_line
			(start -0.67945 0.3048)
			(end -0.120396 0.3048)
			(stroke
				(width 0.1)
				(type default)
			)
			(layer "B.Fab")
		)
		(fp_line
			(start -0.67945 -0.3048)
			(end -0.67945 0.3048)
			(stroke
				(width 0.1)
				(type default)
			)
			(layer "B.Fab")
		)
		(pad "1" smd circle
			(at 0.40005 0)
			(size 0 0)
			(layers "B.Cu" "B.Mask" "B.Paste")
			(net "P0V9_RETIMER_CPU1_VMON")
		)
		(pad "2" smd circle
			(at -0.40005 0)
			(size 0 0)
			(layers "B.Cu" "B.Mask" "B.Paste")
			(net "GND")
		)
	)
	(footprint ""
		(layer "B.Cu")
		(at 328.416158 -401.624546 180)
		(property "Reference" "R1010"
			(at 0 0 0)
			(layer "B.SilkS")
			(hide yes)
			(effects
				(font
					(size 1.27 1.27)
				)
				(justify mirror)
			)
		)
		(property "Value" ""
			(at 0 0 0)
			(layer "B.Fab")
			(effects
				(font
					(size 1.27 1.27)
				)
				(justify mirror)
			)
		)
		(duplicate_pad_numbers_are_jumpers no)
		(fp_line
			(start 1.2954 0.5842)
			(end 1.2954 -0.5842)
			(stroke
				(width 0.1524)
				(type default)
			)
			(layer "B.SilkS")
		)
		(fp_line
			(start 1.2954 -0.5842)
			(end -1.2954 -0.5842)
			(stroke
				(width 0.1524)
				(type default)
			)
			(layer "B.SilkS")
		)
		(fp_line
			(start -1.2954 0.5842)
			(end 1.2954 0.5842)
			(stroke
				(width 0.1524)
				(type default)
			)
			(layer "B.SilkS")
		)
		(fp_line
			(start -1.2954 -0.5842)
			(end -1.2954 0.5842)
			(stroke
				(width 0.1524)
				(type default)
			)
			(layer "B.SilkS")
		)
		(fp_line
			(start 1.1938 0.4064)
			(end 1.1938 -0.406654)
			(stroke
				(width 0.1)
				(type default)
			)
			(layer "B.Fab")
		)
		(fp_line
			(start 1.1938 -0.406654)
			(end 0.8636 -0.406654)
			(stroke
				(width 0.1)
				(type default)
			)
			(layer "B.Fab")
		)
		(fp_line
			(start 0.8636 0.4572)
			(end 0.8636 0.4318)
			(stroke
				(width 0.1)
				(type default)
			)
			(layer "B.Fab")
		)
		(fp_line
			(start 0.8636 0.4318)
			(end 0.8636 0.4064)
			(stroke
				(width 0.1)
				(type default)
			)
			(layer "B.Fab")
		)
		(fp_line
			(start 0.8636 0.4064)
			(end 1.1938 0.4064)
			(stroke
				(width 0.1)
				(type default)
			)
			(layer "B.Fab")
		)
		(fp_line
			(start 0.8636 -0.406654)
			(end 0.8636 -0.4572)
			(stroke
				(width 0.1)
				(type default)
			)
			(layer "B.Fab")
		)
		(fp_line
			(start 0.8636 -0.4572)
			(end -0.8636 -0.4572)
			(stroke
				(width 0.1)
				(type default)
			)
			(layer "B.Fab")
		)
		(fp_line
			(start -0.8636 0.4572)
			(end 0.8636 0.4572)
			(stroke
				(width 0.1)
				(type default)
			)
			(layer "B.Fab")
		)
		(fp_line
			(start -0.8636 0.4064)
			(end -0.8636 0.4572)
			(stroke
				(width 0.1)
				(type default)
			)
			(layer "B.Fab")
		)
		(fp_line
			(start -0.8636 -0.406654)
			(end -1.1938 -0.406654)
			(stroke
				(width 0.1)
				(type default)
			)
			(layer "B.Fab")
		)
		(fp_line
			(start -0.8636 -0.4572)
			(end -0.8636 -0.406654)
			(stroke
				(width 0.1)
				(type default)
			)
			(layer "B.Fab")
		)
		(fp_line
			(start -1.1938 0.4064)
			(end -0.8636 0.4064)
			(stroke
				(width 0.1)
				(type default)
			)
			(layer "B.Fab")
		)
		(fp_line
			(start -1.1938 -0.406654)
			(end -1.1938 0.4064)
			(stroke
				(width 0.1)
				(type default)
			)
			(layer "B.Fab")
		)
		(pad "1" smd rect
			(at 0.7366 0 90)
			(size 0.7112 0.8128)
			(layers "B.Cu" "B.Mask" "B.Paste")
			(net "P0V9_CPU0_RT_2D")
		)
		(pad "2" smd rect
			(at -0.7366 0 90)
			(size 0.7112 0.8128)
			(layers "B.Cu" "B.Mask" "B.Paste")
			(net "P0V9_CPU0_RT1_2A_2D")
		)
	)
	(footprint ""
		(layer "B.Cu")
		(at 228.854 -232.156 -90)
		(property "Reference" "R147"
			(at 0 0 90)
			(layer "B.SilkS")
			(hide yes)
			(effects
				(font
					(size 1.27 1.27)
				)
				(justify mirror)
			)
		)
		(property "Value" ""
			(at 0 0 90)
			(layer "B.Fab")
			(effects
				(font
					(size 1.27 1.27)
				)
				(justify mirror)
			)
		)
		(duplicate_pad_numbers_are_jumpers no)
		(fp_line
			(start -0.7874 0.4064)
			(end 0.7874 0.4064)
			(stroke
				(width 0.1524)
				(type default)
			)
			(layer "B.SilkS")
		)
		(fp_line
			(start 0.7874 0.4064)
			(end 0.7874 -0.4064)
			(stroke
				(width 0.1524)
				(type default)
			)
			(layer "B.SilkS")
		)
		(fp_line
			(start -0.7874 -0.4064)
			(end -0.7874 0.4064)
			(stroke
				(width 0.1524)
				(type default)
			)
			(layer "B.SilkS")
		)
		(fp_line
			(start 0.7874 -0.4064)
			(end -0.7874 -0.4064)
			(stroke
				(width 0.1524)
				(type default)
			)
			(layer "B.SilkS")
		)
		(fp_line
			(start -0.67945 0.3048)
			(end -0.120396 0.3048)
			(stroke
				(width 0.1)
				(type default)
			)
			(layer "B.Fab")
		)
		(fp_line
			(start -0.120396 0.3048)
			(end -0.120396 0.2794)
			(stroke
				(width 0.1)
				(type default)
			)
			(layer "B.Fab")
		)
		(fp_line
			(start 0.12065 0.3048)
			(end 0.67945 0.3048)
			(stroke
				(width 0.1)
				(type default)
			)
			(layer "B.Fab")
		)
		(fp_line
			(start 0.67945 0.3048)
			(end 0.67945 -0.305054)
			(stroke
				(width 0.1)
				(type default)
			)
			(layer "B.Fab")
		)
		(fp_line
			(start -0.120396 0.2794)
			(end 0.12065 0.2794)
			(stroke
				(width 0.1)
				(type default)
			)
			(layer "B.Fab")
		)
		(fp_line
			(start 0.12065 0.2794)
			(end 0.12065 0.3048)
			(stroke
				(width 0.1)
				(type default)
			)
			(layer "B.Fab")
		)
		(fp_line
			(start -0.12065 -0.2794)
			(end -0.12065 -0.3048)
			(stroke
				(width 0.1)
				(type default)
			)
			(layer "B.Fab")
		)
		(fp_line
			(start 0.12065 -0.2794)
			(end -0.12065 -0.2794)
			(stroke
				(width 0.1)
				(type default)
			)
			(layer "B.Fab")
		)
		(fp_line
			(start -0.67945 -0.3048)
			(end -0.67945 0.3048)
			(stroke
				(width 0.1)
				(type default)
			)
			(layer "B.Fab")
		)
		(fp_line
			(start -0.12065 -0.3048)
			(end -0.67945 -0.3048)
			(stroke
				(width 0.1)
				(type default)
			)
			(layer "B.Fab")
		)
		(fp_line
			(start 0.12065 -0.305054)
			(end 0.12065 -0.2794)
			(stroke
				(width 0.1)
				(type default)
			)
			(layer "B.Fab")
		)
		(fp_line
			(start 0.67945 -0.305054)
			(end 0.12065 -0.305054)
			(stroke
				(width 0.1)
				(type default)
			)
			(layer "B.Fab")
		)
		(pad "1" smd circle
			(at 0.40005 0 90)
			(size 0 0)
			(layers "B.Cu" "B.Mask" "B.Paste")
			(net "SMB_CPU0_CPU1_APML_MUX1_SDA")
		)
		(pad "2" smd circle
			(at -0.40005 0 90)
			(size 0 0)
			(layers "B.Cu" "B.Mask" "B.Paste")
			(net "SMB_APML_CPU1_R_SDA")
		)
	)
	(footprint ""
		(layer "B.Cu")
		(at 143.04137 -316.465458 180)
		(property "Reference" "R5030"
			(at 0 0 0)
			(layer "B.SilkS")
			(hide yes)
			(effects
				(font
					(size 1.27 1.27)
				)
				(justify mirror)
			)
		)
		(property "Value" ""
			(at 0 0 0)
			(layer "B.Fab")
			(effects
				(font
					(size 1.27 1.27)
				)
				(justify mirror)
			)
		)
		(duplicate_pad_numbers_are_jumpers no)
		(fp_line
			(start 0.7874 0.4064)
			(end 0.7874 -0.4064)
			(stroke
				(width 0.1524)
				(type default)
			)
			(layer "B.SilkS")
		)
		(fp_line
			(start 0.7874 -0.4064)
			(end -0.7874 -0.4064)
			(stroke
				(width 0.1524)
				(type default)
			)
			(layer "B.SilkS")
		)
		(fp_line
			(start -0.7874 0.4064)
			(end 0.7874 0.4064)
			(stroke
				(width 0.1524)
				(type default)
			)
			(layer "B.SilkS")
		)
		(fp_line
			(start -0.7874 -0.4064)
			(end -0.7874 0.4064)
			(stroke
				(width 0.1524)
				(type default)
			)
			(layer "B.SilkS")
		)
		(fp_line
			(start 0.67945 0.3048)
			(end 0.67945 -0.305054)
			(stroke
				(width 0.1)
				(type default)
			)
			(layer "B.Fab")
		)
		(fp_line
			(start 0.67945 -0.305054)
			(end 0.12065 -0.305054)
			(stroke
				(width 0.1)
				(type default)
			)
			(layer "B.Fab")
		)
		(fp_line
			(start 0.12065 0.3048)
			(end 0.67945 0.3048)
			(stroke
				(width 0.1)
				(type default)
			)
			(layer "B.Fab")
		)
		(fp_line
			(start 0.12065 0.2794)
			(end 0.12065 0.3048)
			(stroke
				(width 0.1)
				(type default)
			)
			(layer "B.Fab")
		)
		(fp_line
			(start 0.12065 -0.2794)
			(end -0.12065 -0.2794)
			(stroke
				(width 0.1)
				(type default)
			)
			(layer "B.Fab")
		)
		(fp_line
			(start 0.12065 -0.305054)
			(end 0.12065 -0.2794)
			(stroke
				(width 0.1)
				(type default)
			)
			(layer "B.Fab")
		)
		(fp_line
			(start -0.120396 0.3048)
			(end -0.120396 0.2794)
			(stroke
				(width 0.1)
				(type default)
			)
			(layer "B.Fab")
		)
		(fp_line
			(start -0.120396 0.2794)
			(end 0.12065 0.2794)
			(stroke
				(width 0.1)
				(type default)
			)
			(layer "B.Fab")
		)
		(fp_line
			(start -0.12065 -0.2794)
			(end -0.12065 -0.3048)
			(stroke
				(width 0.1)
				(type default)
			)
			(layer "B.Fab")
		)
		(fp_line
			(start -0.12065 -0.3048)
			(end -0.67945 -0.3048)
			(stroke
				(width 0.1)
				(type default)
			)
			(layer "B.Fab")
		)
		(fp_line
			(start -0.67945 0.3048)
			(end -0.120396 0.3048)
			(stroke
				(width 0.1)
				(type default)
			)
			(layer "B.Fab")
		)
		(fp_line
			(start -0.67945 -0.3048)
			(end -0.67945 0.3048)
			(stroke
				(width 0.1)
				(type default)
			)
			(layer "B.Fab")
		)
		(pad "1" smd circle
			(at 0.40005 0)
			(size 0 0)
			(layers "B.Cu" "B.Mask" "B.Paste")
			(net "GND")
		)
		(pad "2" smd circle
			(at -0.40005 0)
			(size 0 0)
			(layers "B.Cu" "B.Mask" "B.Paste")
			(net "FM_BMC_TPM_PRES_N")
		)
	)
	(footprint ""
		(layer "B.Cu")
		(at 18.039588 -395.703806)
		(property "Reference" "PC6618"
			(at 0 0 0)
			(layer "B.SilkS")
			(hide yes)
			(effects
				(font
					(size 1.27 1.27)
				)
				(justify mirror)
			)
		)
		(property "Value" ""
			(at 0 0 0)
			(layer "B.Fab")
			(effects
				(font
					(size 1.27 1.27)
				)
				(justify mirror)
			)
		)
		(duplicate_pad_numbers_are_jumpers no)
		(fp_line
			(start -1.524 -0.762)
			(end -1.524 0.762)
			(stroke
				(width 0.1524)
				(type default)
			)
			(layer "B.SilkS")
		)
		(fp_line
			(start -1.524 0.762)
			(end 1.524 0.762)
			(stroke
				(width 0.1524)
				(type default)
			)
			(layer "B.SilkS")
		)
		(fp_line
			(start 1.524 -0.762)
			(end -1.524 -0.762)
			(stroke
				(width 0.1524)
				(type default)
			)
			(layer "B.SilkS")
		)
		(fp_line
			(start 1.524 0.762)
			(end 1.524 -0.762)
			(stroke
				(width 0.1524)
				(type default)
			)
			(layer "B.SilkS")
		)
		(fp_line
			(start -1.1049 -0.724916)
			(end 1.1049 -0.724916)
			(stroke
				(width 0.1)
				(type default)
			)
			(layer "B.Fab")
		)
		(fp_line
			(start -1.1049 0.724916)
			(end -1.1049 -0.724916)
			(stroke
				(width 0.1)
				(type default)
			)
			(layer "B.Fab")
		)
		(fp_line
			(start 1.1049 -0.724916)
			(end 1.1049 0.724916)
			(stroke
				(width 0.1)
				(type default)
			)
			(layer "B.Fab")
		)
		(fp_line
			(start 1.1049 0.724916)
			(end -1.1049 0.724916)
			(stroke
				(width 0.1)
				(type default)
			)
			(layer "B.Fab")
		)
		(pad "1" smd rect
			(at 0.889 0)
			(size 1.016 1.27)
			(layers "B.Cu" "B.Mask" "B.Paste")
			(net "SW_P12V_AUX_P0V9_RETIMER_CPU1_FLT")
		)
		(pad "2" smd rect
			(at -0.889 0)
			(size 1.016 1.27)
			(layers "B.Cu" "B.Mask" "B.Paste")
			(net "GND")
		)
	)
	(footprint ""
		(layer "B.Cu")
		(at 124.459492 -72.616822 180)
		(property "Reference" "R6241"
			(at 0 0 0)
			(layer "B.SilkS")
			(hide yes)
			(effects
				(font
					(size 1.27 1.27)
				)
				(justify mirror)
			)
		)
		(property "Value" ""
			(at 0 0 0)
			(layer "B.Fab")
			(effects
				(font
					(size 1.27 1.27)
				)
				(justify mirror)
			)
		)
		(duplicate_pad_numbers_are_jumpers no)
		(fp_line
			(start 0.7874 0.4064)
			(end 0.7874 -0.4064)
			(stroke
				(width 0.1524)
				(type default)
			)
			(layer "B.SilkS")
		)
		(fp_line
			(start 0.7874 -0.4064)
			(end -0.7874 -0.4064)
			(stroke
				(width 0.1524)
				(type default)
			)
			(layer "B.SilkS")
		)
		(fp_line
			(start -0.7874 0.4064)
			(end 0.7874 0.4064)
			(stroke
				(width 0.1524)
				(type default)
			)
			(layer "B.SilkS")
		)
		(fp_line
			(start -0.7874 -0.4064)
			(end -0.7874 0.4064)
			(stroke
				(width 0.1524)
				(type default)
			)
			(layer "B.SilkS")
		)
		(fp_line
			(start 0.67945 0.3048)
			(end 0.67945 -0.305054)
			(stroke
				(width 0.1)
				(type default)
			)
			(layer "B.Fab")
		)
		(fp_line
			(start 0.67945 -0.305054)
			(end 0.12065 -0.305054)
			(stroke
				(width 0.1)
				(type default)
			)
			(layer "B.Fab")
		)
		(fp_line
			(start 0.12065 0.3048)
			(end 0.67945 0.3048)
			(stroke
				(width 0.1)
				(type default)
			)
			(layer "B.Fab")
		)
		(fp_line
			(start 0.12065 0.2794)
			(end 0.12065 0.3048)
			(stroke
				(width 0.1)
				(type default)
			)
			(layer "B.Fab")
		)
		(fp_line
			(start 0.12065 -0.2794)
			(end -0.12065 -0.2794)
			(stroke
				(width 0.1)
				(type default)
			)
			(layer "B.Fab")
		)
		(fp_line
			(start 0.12065 -0.305054)
			(end 0.12065 -0.2794)
			(stroke
				(width 0.1)
				(type default)
			)
			(layer "B.Fab")
		)
		(fp_line
			(start -0.120396 0.3048)
			(end -0.120396 0.2794)
			(stroke
				(width 0.1)
				(type default)
			)
			(layer "B.Fab")
		)
		(fp_line
			(start -0.120396 0.2794)
			(end 0.12065 0.2794)
			(stroke
				(width 0.1)
				(type default)
			)
			(layer "B.Fab")
		)
		(fp_line
			(start -0.12065 -0.2794)
			(end -0.12065 -0.3048)
			(stroke
				(width 0.1)
				(type default)
			)
			(layer "B.Fab")
		)
		(fp_line
			(start -0.12065 -0.3048)
			(end -0.67945 -0.3048)
			(stroke
				(width 0.1)
				(type default)
			)
			(layer "B.Fab")
		)
		(fp_line
			(start -0.67945 0.3048)
			(end -0.120396 0.3048)
			(stroke
				(width 0.1)
				(type default)
			)
			(layer "B.Fab")
		)
		(fp_line
			(start -0.67945 -0.3048)
			(end -0.67945 0.3048)
			(stroke
				(width 0.1)
				(type default)
			)
			(layer "B.Fab")
		)
		(pad "1" smd circle
			(at 0.40005 0)
			(size 0 0)
			(layers "B.Cu" "B.Mask" "B.Paste")
			(net "PWRGD_P1V2_AUX")
		)
		(pad "2" smd circle
			(at -0.40005 0)
			(size 0 0)
			(layers "B.Cu" "B.Mask" "B.Paste")
			(net "PWRGD_P1V2_AUX_R")
		)
	)
)
